# T6G (Grand Teton) — schematic netlist excerpt (pin names and nets, part order shuffled) for the footprints in the layout excerpt that follows; sources: Cadence DE-HDL packaged netlist, KiCad conversion of 04192023_DAF0TMB3IC0_F0TG_MB_C_brd_V02_OCP.brd

PL30  Q_INDUCTOR  50NH/86A IND  pkg SMLF  page 211 : \1\ = SW_P12V_AUX_PVDDCR_CPU0_P1_FLT ; \2\ = P12V_AUX
PC404_3  Q_CAP  0.1UF 25V 10% X7R  pkg 0402  page 219 : A = PVDDCR_CPU1_P1_VCCS ; B = GND
C855  Q_CAP_DIFFBUS  DIFF BUS_0.22UF 6.3V 20% X6S  pkg C0201  page 64 : \1\ = P5E_CPU0_P2_TX_C_DP<7> ; \2\ = P5E_CPU0_P2_TX_DP<7>

(kicad_pcb
	(version 20260206)
	(generator "pcbnew")
	(generator_version "10.0")
	(general
		(thickness 1.6)
		(legacy_teardrops no)
	)
	(paper "A4")
	(title_block
		(title "04192023_DAF0TMB3IC0_F0TG_MB_C_brd_V02_OCP.brd")
		(comment 1 "Grand Teton / footprints 645-647 of 8354")
	)
	(layers
		(0 "F.Cu" signal "TOP")
		(4 "In1.Cu" signal "GND")
		(6 "In2.Cu" signal "IN1")
		(8 "In3.Cu" signal "GND1")
		(10 "In4.Cu" signal "IN2")
		(12 "In5.Cu" signal "GND2")
		(14 "In6.Cu" signal "IN3")
		(16 "In7.Cu" signal "GND3")
		(18 "In8.Cu" signal "VCC")
		(20 "In9.Cu" signal "VCC1")
		(22 "In10.Cu" signal "GND4")
		(24 "In11.Cu" signal "IN4")
		(26 "In12.Cu" signal "GND5")
		(28 "In13.Cu" signal "IN5")
		(30 "In14.Cu" signal "GND6")
		(32 "In15.Cu" signal "IN6")
		(34 "In16.Cu" signal "GND7")
		(2 "B.Cu" signal "BOTTOM")
		(9 "F.Adhes" user "F.Adhesive")
		(11 "B.Adhes" user "B.Adhesive")
		(13 "F.Paste" user "Package Geometry/Pastemask Top")
		(15 "B.Paste" user "Package Geometry/Pastemask Bottom")
		(5 "F.SilkS" user "Ref Des/Silkscreen Top")
		(7 "B.SilkS" user "Ref Des/Silkscreen Bottom")
		(1 "F.Mask" user "Board Geometry/Soldermask Top")
		(3 "B.Mask" user "Board Geometry/Soldermask Bottom")
		(17 "Dwgs.User" user "User.Drawings")
		(19 "Cmts.User" user "User.Comments")
		(21 "Eco1.User" user "User.Eco1")
		(23 "Eco2.User" user "User.Eco2")
		(25 "Edge.Cuts" user "Board Geometry/Outline")
		(27 "Margin" user)
		(31 "F.CrtYd" user "Package Geometry/Place Bound Top")
		(29 "B.CrtYd" user "Package Geometry/Place Bound Bottom")
		(35 "F.Fab" user "Ref Des/Assembly Top")
		(33 "B.Fab" user "Ref Des/Assembly Bottom")
	)
	(footprint ""
		(layer "F.Cu")
		(at 67.71513 -339.857588 90)
		(property "Reference" "PC404_3"
			(at 0 0 90)
			(layer "F.SilkS")
			(hide yes)
			(effects
				(font
					(size 1.27 1.27)
				)
			)
		)
		(property "Value" ""
			(at 0 0 90)
			(layer "F.Fab")
			(effects
				(font
					(size 1.27 1.27)
				)
			)
		)
		(duplicate_pad_numbers_are_jumpers no)
		(fp_line
			(start 0.7874 -0.4064)
			(end 0.7874 0.4064)
			(stroke
				(width 0.1524)
				(type default)
			)
			(layer "F.SilkS")
		)
		(fp_line
			(start -0.7874 -0.4064)
			(end 0.7874 -0.4064)
			(stroke
				(width 0.1524)
				(type default)
			)
			(layer "F.SilkS")
		)
		(fp_line
			(start 0.7874 0.4064)
			(end -0.7874 0.4064)
			(stroke
				(width 0.1524)
				(type default)
			)
			(layer "F.SilkS")
		)
		(fp_line
			(start -0.7874 0.4064)
			(end -0.7874 -0.4064)
			(stroke
				(width 0.1524)
				(type default)
			)
			(layer "F.SilkS")
		)
		(fp_line
			(start -0.12065 -0.305054)
			(end -0.12065 -0.2794)
			(stroke
				(width 0.1)
				(type default)
			)
			(layer "F.Fab")
		)
		(fp_line
			(start -0.67945 -0.305054)
			(end -0.12065 -0.305054)
			(stroke
				(width 0.1)
				(type default)
			)
			(layer "F.Fab")
		)
		(fp_line
			(start 0.67945 -0.3048)
			(end 0.67945 0.3048)
			(stroke
				(width 0.1)
				(type default)
			)
			(layer "F.Fab")
		)
		(fp_line
			(start 0.12065 -0.3048)
			(end 0.67945 -0.3048)
			(stroke
				(width 0.1)
				(type default)
			)
			(layer "F.Fab")
		)
		(fp_line
			(start 0.12065 -0.2794)
			(end 0.12065 -0.3048)
			(stroke
				(width 0.1)
				(type default)
			)
			(layer "F.Fab")
		)
		(fp_line
			(start -0.12065 -0.2794)
			(end 0.12065 -0.2794)
			(stroke
				(width 0.1)
				(type default)
			)
			(layer "F.Fab")
		)
		(fp_line
			(start 0.120396 0.2794)
			(end -0.12065 0.2794)
			(stroke
				(width 0.1)
				(type default)
			)
			(layer "F.Fab")
		)
		(fp_line
			(start -0.12065 0.2794)
			(end -0.12065 0.3048)
			(stroke
				(width 0.1)
				(type default)
			)
			(layer "F.Fab")
		)
		(fp_line
			(start 0.67945 0.3048)
			(end 0.120396 0.3048)
			(stroke
				(width 0.1)
				(type default)
			)
			(layer "F.Fab")
		)
		(fp_line
			(start 0.120396 0.3048)
			(end 0.120396 0.2794)
			(stroke
				(width 0.1)
				(type default)
			)
			(layer "F.Fab")
		)
		(fp_line
			(start -0.12065 0.3048)
			(end -0.67945 0.3048)
			(stroke
				(width 0.1)
				(type default)
			)
			(layer "F.Fab")
		)
		(fp_line
			(start -0.67945 0.3048)
			(end -0.67945 -0.305054)
			(stroke
				(width 0.1)
				(type default)
			)
			(layer "F.Fab")
		)
		(pad "1" smd circle
			(at -0.40005 0 90)
			(size 0 0)
			(layers "F.Cu" "F.Mask" "F.Paste")
			(net "PVDDCR_CPU1_P1_VCCS")
		)
		(pad "2" smd circle
			(at 0.40005 0 90)
			(size 0 0)
			(layers "F.Cu" "F.Mask" "F.Paste")
			(net "GND")
		)
	)
	(footprint ""
		(layer "F.Cu")
		(at 410.53004 -383.88163 -90)
		(property "Reference" "C855"
			(at 0 0 270)
			(layer "F.SilkS")
			(hide yes)
			(effects
				(font
					(size 1.27 1.27)
				)
			)
		)
		(property "Value" ""
			(at 0 0 270)
			(layer "F.Fab")
			(effects
				(font
					(size 1.27 1.27)
				)
			)
		)
		(duplicate_pad_numbers_are_jumpers no)
		(fp_line
			(start -0.299974 0.150114)
			(end -0.299974 -0.150114)
			(stroke
				(width 0.1)
				(type default)
			)
			(layer "F.Fab")
		)
		(fp_line
			(start 0.299974 0.150114)
			(end -0.299974 0.150114)
			(stroke
				(width 0.1)
				(type default)
			)
			(layer "F.Fab")
		)
		(fp_line
			(start -0.299974 -0.150114)
			(end 0.299974 -0.150114)
			(stroke
				(width 0.1)
				(type default)
			)
			(layer "F.Fab")
		)
		(fp_line
			(start 0.299974 -0.150114)
			(end 0.299974 0.150114)
			(stroke
				(width 0.1)
				(type default)
			)
			(layer "F.Fab")
		)
		(pad "1" smd rect
			(at -0.2667 0 270)
			(size 0.3048 0.381)
			(layers "F.Cu" "F.Mask" "F.Paste")
			(net "P5E_CPU0_P2_TX_C_DP<7>")
		)
		(pad "2" smd rect
			(at 0.2667 0 270)
			(size 0.3048 0.381)
			(layers "F.Cu" "F.Mask" "F.Paste")
			(net "P5E_CPU0_P2_TX_DP<7>")
		)
	)
	(footprint ""
		(layer "F.Cu")
		(at 88.23452 -159.029908 -90)
		(property "Reference" "PL30"
			(at -0.049784 -3.804412 90)
			(unlocked yes)
			(layer "F.SilkS")
			(effects
				(font
					(size 0.7874 0.5842)
					(thickness 0.1524)
				)
				(justify left)
			)
		)
		(property "Value" ""
			(at 0 0 270)
			(layer "F.Fab")
			(effects
				(font
					(size 1.27 1.27)
				)
			)
		)
		(duplicate_pad_numbers_are_jumpers no)
		(fp_line
			(start -3.050032 2.999994)
			(end 3.050032 2.999994)
			(stroke
				(width 0.1524)
				(type default)
			)
			(layer "F.SilkS")
		)
		(fp_line
			(start 3.050032 2.999994)
			(end 3.050032 1.4478)
			(stroke
				(width 0.1524)
				(type default)
			)
			(layer "F.SilkS")
		)
		(fp_line
			(start -3.050032 1.4478)
			(end -3.050032 2.999994)
			(stroke
				(width 0.1524)
				(type default)
			)
			(layer "F.SilkS")
		)
		(fp_line
			(start 3.050032 -1.4478)
			(end 3.050032 -2.999994)
			(stroke
				(width 0.1524)
				(type default)
			)
			(layer "F.SilkS")
		)
		(fp_line
			(start -3.050032 -2.999994)
			(end -3.050032 -1.4478)
			(stroke
				(width 0.1524)
				(type default)
			)
			(layer "F.SilkS")
		)
		(fp_line
			(start 3.050032 -2.999994)
			(end -3.050032 -2.999994)
			(stroke
				(width 0.1524)
				(type default)
			)
			(layer "F.SilkS")
		)
		(fp_line
			(start -3.050032 2.999994)
			(end 3.050032 2.999994)
			(stroke
				(width 0.1)
				(type default)
			)
			(layer "F.Fab")
		)
		(fp_line
			(start 3.050032 2.999994)
			(end 3.050032 -2.999994)
			(stroke
				(width 0.1)
				(type default)
			)
			(layer "F.Fab")
		)
		(fp_line
			(start -3.050032 -2.999994)
			(end -3.050032 2.999994)
			(stroke
				(width 0.1)
				(type default)
			)
			(layer "F.Fab")
		)
		(fp_line
			(start 3.050032 -2.999994)
			(end -3.050032 -2.999994)
			(stroke
				(width 0.1)
				(type default)
			)
			(layer "F.Fab")
		)
		(pad "1" smd rect
			(at -2.525014 0 270)
			(size 1.651 2.6162)
			(layers "F.Cu" "F.Mask" "F.Paste")
			(net "SW_P12V_AUX_PVDDCR_CPU0_P1_FLT")
		)
		(pad "2" smd rect
			(at 2.525014 0 270)
			(size 1.651 2.6162)
			(layers "F.Cu" "F.Mask" "F.Paste")
			(net "P12V_AUX")
		)
	)
)
